# T6G (Grand Teton) — schematic netlist excerpt (pin names and nets, part order shuffled) for the footprints in the layout excerpt that follows; sources: Cadence DE-HDL packaged netlist, KiCad conversion of 04192023_DAF0TMB3IC0_F0TG_MB_C_brd_V02_OCP.brd

R782  Q_RES  10K 1% CHIP  pkg 0201LF  page 331 : A = GPIO2_RT_CPU1_P1 ; B = GND
PC292_3  Q_CAP  1UF 25V 10% X6S  pkg C0402  page 212 : A = SW_P12V_AUX_PVDDCR_CPU0_P1_FLT ; B = GND
R6056  Q_RES  0 5% CHIP  pkg 0402LF  page 139 : A = RST_PERST_OCP_V3_2_BUF2_N ; B = RST_PERST0_OCP_V3_2_N

(kicad_pcb
	(version 20260206)
	(generator "pcbnew")
	(generator_version "10.0")
	(general
		(thickness 1.6)
		(legacy_teardrops no)
	)
	(paper "A4")
	(title_block
		(title "04192023_DAF0TMB3IC0_F0TG_MB_C_brd_V02_OCP.brd")
		(comment 1 "Grand Teton / footprints 87-89 of 8354")
	)
	(layers
		(0 "F.Cu" signal "TOP")
		(4 "In1.Cu" signal "GND")
		(6 "In2.Cu" signal "IN1")
		(8 "In3.Cu" signal "GND1")
		(10 "In4.Cu" signal "IN2")
		(12 "In5.Cu" signal "GND2")
		(14 "In6.Cu" signal "IN3")
		(16 "In7.Cu" signal "GND3")
		(18 "In8.Cu" signal "VCC")
		(20 "In9.Cu" signal "VCC1")
		(22 "In10.Cu" signal "GND4")
		(24 "In11.Cu" signal "IN4")
		(26 "In12.Cu" signal "GND5")
		(28 "In13.Cu" signal "IN5")
		(30 "In14.Cu" signal "GND6")
		(32 "In15.Cu" signal "IN6")
		(34 "In16.Cu" signal "GND7")
		(2 "B.Cu" signal "BOTTOM")
		(9 "F.Adhes" user "F.Adhesive")
		(11 "B.Adhes" user "B.Adhesive")
		(13 "F.Paste" user "Package Geometry/Pastemask Top")
		(15 "B.Paste" user "Package Geometry/Pastemask Bottom")
		(5 "F.SilkS" user "Ref Des/Silkscreen Top")
		(7 "B.SilkS" user "Ref Des/Silkscreen Bottom")
		(1 "F.Mask" user "Board Geometry/Soldermask Top")
		(3 "B.Mask" user "Board Geometry/Soldermask Bottom")
		(17 "Dwgs.User" user "User.Drawings")
		(19 "Cmts.User" user "User.Comments")
		(21 "Eco1.User" user "User.Eco1")
		(23 "Eco2.User" user "User.Eco2")
		(25 "Edge.Cuts" user "Board Geometry/Outline")
		(27 "Margin" user)
		(31 "F.CrtYd" user "Package Geometry/Place Bound Top")
		(29 "B.CrtYd" user "Package Geometry/Place Bound Bottom")
		(35 "F.Fab" user "Ref Des/Assembly Top")
		(33 "B.Fab" user "Ref Des/Assembly Bottom")
	)
	(footprint ""
		(layer "F.Cu")
		(at 95.428816 -182.616602 90)
		(property "Reference" "PC292_3"
			(at 0 0 90)
			(layer "F.SilkS")
			(hide yes)
			(effects
				(font
					(size 1.27 1.27)
				)
			)
		)
		(property "Value" ""
			(at 0 0 90)
			(layer "F.Fab")
			(effects
				(font
					(size 1.27 1.27)
				)
			)
		)
		(duplicate_pad_numbers_are_jumpers no)
		(fp_line
			(start 0.7874 -0.4064)
			(end 0.7874 0.4064)
			(stroke
				(width 0.1524)
				(type default)
			)
			(layer "F.SilkS")
		)
		(fp_line
			(start -0.7874 -0.4064)
			(end 0.7874 -0.4064)
			(stroke
				(width 0.1524)
				(type default)
			)
			(layer "F.SilkS")
		)
		(fp_line
			(start 0.7874 0.4064)
			(end -0.7874 0.4064)
			(stroke
				(width 0.1524)
				(type default)
			)
			(layer "F.SilkS")
		)
		(fp_line
			(start -0.7874 0.4064)
			(end -0.7874 -0.4064)
			(stroke
				(width 0.1524)
				(type default)
			)
			(layer "F.SilkS")
		)
		(fp_line
			(start -0.12065 -0.305054)
			(end -0.12065 -0.2794)
			(stroke
				(width 0.1)
				(type default)
			)
			(layer "F.Fab")
		)
		(fp_line
			(start -0.67945 -0.305054)
			(end -0.12065 -0.305054)
			(stroke
				(width 0.1)
				(type default)
			)
			(layer "F.Fab")
		)
		(fp_line
			(start 0.67945 -0.3048)
			(end 0.67945 0.3048)
			(stroke
				(width 0.1)
				(type default)
			)
			(layer "F.Fab")
		)
		(fp_line
			(start 0.12065 -0.3048)
			(end 0.67945 -0.3048)
			(stroke
				(width 0.1)
				(type default)
			)
			(layer "F.Fab")
		)
		(fp_line
			(start 0.12065 -0.2794)
			(end 0.12065 -0.3048)
			(stroke
				(width 0.1)
				(type default)
			)
			(layer "F.Fab")
		)
		(fp_line
			(start -0.12065 -0.2794)
			(end 0.12065 -0.2794)
			(stroke
				(width 0.1)
				(type default)
			)
			(layer "F.Fab")
		)
		(fp_line
			(start 0.120396 0.2794)
			(end -0.12065 0.2794)
			(stroke
				(width 0.1)
				(type default)
			)
			(layer "F.Fab")
		)
		(fp_line
			(start -0.12065 0.2794)
			(end -0.12065 0.3048)
			(stroke
				(width 0.1)
				(type default)
			)
			(layer "F.Fab")
		)
		(fp_line
			(start 0.67945 0.3048)
			(end 0.120396 0.3048)
			(stroke
				(width 0.1)
				(type default)
			)
			(layer "F.Fab")
		)
		(fp_line
			(start 0.120396 0.3048)
			(end 0.120396 0.2794)
			(stroke
				(width 0.1)
				(type default)
			)
			(layer "F.Fab")
		)
		(fp_line
			(start -0.12065 0.3048)
			(end -0.67945 0.3048)
			(stroke
				(width 0.1)
				(type default)
			)
			(layer "F.Fab")
		)
		(fp_line
			(start -0.67945 0.3048)
			(end -0.67945 -0.305054)
			(stroke
				(width 0.1)
				(type default)
			)
			(layer "F.Fab")
		)
		(pad "1" smd circle
			(at -0.40005 0 90)
			(size 0 0)
			(layers "F.Cu" "F.Mask" "F.Paste")
			(net "SW_P12V_AUX_PVDDCR_CPU0_P1_FLT")
		)
		(pad "2" smd circle
			(at 0.40005 0 90)
			(size 0 0)
			(layers "F.Cu" "F.Mask" "F.Paste")
			(net "GND")
		)
	)
	(footprint ""
		(layer "F.Cu")
		(at 83.222084 -40.67048 180)
		(property "Reference" "R6056"
			(at 0 0 180)
			(layer "F.SilkS")
			(hide yes)
			(effects
				(font
					(size 1.27 1.27)
				)
			)
		)
		(property "Value" ""
			(at 0 0 180)
			(layer "F.Fab")
			(effects
				(font
					(size 1.27 1.27)
				)
			)
		)
		(duplicate_pad_numbers_are_jumpers no)
		(fp_line
			(start 0.7874 0.4064)
			(end -0.7874 0.4064)
			(stroke
				(width 0.1524)
				(type default)
			)
			(layer "F.SilkS")
		)
		(fp_line
			(start 0.7874 -0.4064)
			(end 0.7874 0.4064)
			(stroke
				(width 0.1524)
				(type default)
			)
			(layer "F.SilkS")
		)
		(fp_line
			(start -0.7874 0.4064)
			(end -0.7874 -0.4064)
			(stroke
				(width 0.1524)
				(type default)
			)
			(layer "F.SilkS")
		)
		(fp_line
			(start -0.7874 -0.4064)
			(end 0.7874 -0.4064)
			(stroke
				(width 0.1524)
				(type default)
			)
			(layer "F.SilkS")
		)
		(fp_line
			(start 0.67945 0.3048)
			(end 0.120396 0.3048)
			(stroke
				(width 0.1)
				(type default)
			)
			(layer "F.Fab")
		)
		(fp_line
			(start 0.67945 -0.3048)
			(end 0.67945 0.3048)
			(stroke
				(width 0.1)
				(type default)
			)
			(layer "F.Fab")
		)
		(fp_line
			(start 0.12065 -0.2794)
			(end 0.12065 -0.3048)
			(stroke
				(width 0.1)
				(type default)
			)
			(layer "F.Fab")
		)
		(fp_line
			(start 0.12065 -0.3048)
			(end 0.67945 -0.3048)
			(stroke
				(width 0.1)
				(type default)
			)
			(layer "F.Fab")
		)
		(fp_line
			(start 0.120396 0.3048)
			(end 0.120396 0.2794)
			(stroke
				(width 0.1)
				(type default)
			)
			(layer "F.Fab")
		)
		(fp_line
			(start 0.120396 0.2794)
			(end -0.12065 0.2794)
			(stroke
				(width 0.1)
				(type default)
			)
			(layer "F.Fab")
		)
		(fp_line
			(start -0.12065 0.3048)
			(end -0.67945 0.3048)
			(stroke
				(width 0.1)
				(type default)
			)
			(layer "F.Fab")
		)
		(fp_line
			(start -0.12065 0.2794)
			(end -0.12065 0.3048)
			(stroke
				(width 0.1)
				(type default)
			)
			(layer "F.Fab")
		)
		(fp_line
			(start -0.12065 -0.2794)
			(end 0.12065 -0.2794)
			(stroke
				(width 0.1)
				(type default)
			)
			(layer "F.Fab")
		)
		(fp_line
			(start -0.12065 -0.305054)
			(end -0.12065 -0.2794)
			(stroke
				(width 0.1)
				(type default)
			)
			(layer "F.Fab")
		)
		(fp_line
			(start -0.67945 0.3048)
			(end -0.67945 -0.305054)
			(stroke
				(width 0.1)
				(type default)
			)
			(layer "F.Fab")
		)
		(fp_line
			(start -0.67945 -0.305054)
			(end -0.12065 -0.305054)
			(stroke
				(width 0.1)
				(type default)
			)
			(layer "F.Fab")
		)
		(pad "1" smd circle
			(at -0.40005 0 180)
			(size 0 0)
			(layers "F.Cu" "F.Mask" "F.Paste")
			(net "RST_PERST_OCP_V3_2_BUF2_N")
		)
		(pad "2" smd circle
			(at 0.40005 0 180)
			(size 0 0)
			(layers "F.Cu" "F.Mask" "F.Paste")
			(net "RST_PERST0_OCP_V3_2_N")
		)
	)
	(footprint ""
		(layer "F.Cu")
		(at 75.7936 -385.58216)
		(property "Reference" "R782"
			(at 0 0 0)
			(layer "F.SilkS")
			(hide yes)
			(effects
				(font
					(size 1.27 1.27)
				)
			)
		)
		(property "Value" ""
			(at 0 0 0)
			(layer "F.Fab")
			(effects
				(font
					(size 1.27 1.27)
				)
			)
		)
		(duplicate_pad_numbers_are_jumpers no)
		(fp_line
			(start -0.32512 -0.175006)
			(end 0.32512 -0.175006)
			(stroke
				(width 0.1)
				(type default)
			)
			(layer "F.Fab")
		)
		(fp_line
			(start -0.32512 0.175006)
			(end -0.32512 -0.175006)
			(stroke
				(width 0.1)
				(type default)
			)
			(layer "F.Fab")
		)
		(fp_line
			(start 0.32512 -0.175006)
			(end 0.32512 0.175006)
			(stroke
				(width 0.1)
				(type default)
			)
			(layer "F.Fab")
		)
		(fp_line
			(start 0.32512 0.175006)
			(end -0.32512 0.175006)
			(stroke
				(width 0.1)
				(type default)
			)
			(layer "F.Fab")
		)
		(pad "1" smd rect
			(at -0.2667 0)
			(size 0.3048 0.381)
			(layers "F.Cu" "F.Mask" "F.Paste")
			(net "GPIO2_RT_CPU1_P1")
		)
		(pad "2" smd rect
			(at 0.2667 0 180)
			(size 0.3048 0.381)
			(layers "F.Cu" "F.Mask" "F.Paste")
			(net "GND")
		)
	)
)
